(kicad_pcb
	(version 20241229)
	(generator "pcbnew")
	(generator_version "9.0")
	(general
		(thickness 1.599998)
		(legacy_teardrops no)
	)
	(paper "A4")
	(title_block
		(title "Artix - Datacenter Secure Control Module (DC-SCM)")
		(date "2024-11-06")
		(rev "1.1.3")
		(comment 9 "footprints 213-213 of 544")
	)
	(layers
		(0 "F.Cu" signal)
		(4 "In1.Cu" signal)
		(6 "In2.Cu" signal)
		(8 "In3.Cu" signal)
		(10 "In4.Cu" signal)
		(12 "In5.Cu" signal)
		(14 "In6.Cu" signal)
		(2 "B.Cu" signal)
		(9 "F.Adhes" user "F.Adhesive")
		(11 "B.Adhes" user "B.Adhesive")
		(13 "F.Paste" user)
		(15 "B.Paste" user)
		(5 "F.SilkS" user "F.Silkscreen")
		(7 "B.SilkS" user "B.Silkscreen")
		(1 "F.Mask" user)
		(3 "B.Mask" user)
		(17 "Dwgs.User" user "User.Drawings")
		(19 "Cmts.User" user "User.Comments")
		(21 "Eco1.User" user "User.Eco1")
		(23 "Eco2.User" user "User.Eco2")
		(25 "Edge.Cuts" user)
		(27 "Margin" user)
		(31 "F.CrtYd" user "F.Courtyard")
		(29 "B.CrtYd" user "B.Courtyard")
		(35 "F.Fab" user)
		(33 "B.Fab" user)
	)
	(footprint "antmicro-footprints:R_0402_1005Metric"
		(layer "F.Cu")
		(at 90.59 164.39 180)
		(descr "Resistor SMD 0402")
		(tags "resistor SMD 0402")
		(property "Reference" "R62"
			(at -3.09 -0.91 0)
			(layer "F.SilkS")
			(effects
				(font
					(size 0.7 0.7)
					(thickness 0.15)
				)
				(justify right bottom)
			)
		)
		(property "Value" "R_200k_0402"
			(at 0 1.4 0)
			(layer "F.Fab")
			(effects
				(font
					(size 0.7 0.7)
					(thickness 0.15)
				)
				(justify right bottom)
			)
		)
		(property "Datasheet" "https://www.bourns.com/docs/product-datasheets/cr.pdf"
			(at 0 0 180)
			(layer "F.Fab")
			(hide yes)
			(effects
				(font
					(size 1.27 1.27)
					(thickness 0.15)
				)
			)
		)
		(property "Description" "SMD Chip Resistor, 200 kohm, ± 1%, 62.5 mW, 0402 [1005 Metric], Thick Film, General Purpose"
			(at 0 0 180)
			(layer "F.Fab")
			(hide yes)
			(effects
				(font
					(size 1.27 1.27)
					(thickness 0.15)
				)
			)
		)
		(property "Author" "Antmicro"
			(at 181.18 328.78 0)
			(layer "F.Fab")
			(hide yes)
			(effects
				(font
					(size 1 1)
					(thickness 0.15)
				)
			)
		)
		(property "License" "Apache-2.0"
			(at 181.18 328.78 0)
			(layer "F.Fab")
			(hide yes)
			(effects
				(font
					(size 1 1)
					(thickness 0.15)
				)
			)
		)
		(property "MPN" "CR0402-FX-2003GLF"
			(at 181.18 328.78 0)
			(layer "F.Fab")
			(hide yes)
			(effects
				(font
					(size 1 1)
					(thickness 0.15)
				)
			)
		)
		(property "Manufacturer" "Bourns"
			(at 181.18 328.78 0)
			(layer "F.Fab")
			(hide yes)
			(effects
				(font
					(size 1 1)
					(thickness 0.15)
				)
			)
		)
		(property "Tolerance" "1%"
			(at 181.18 328.78 0)
			(layer "F.Fab")
			(hide yes)
			(effects
				(font
					(size 1 1)
					(thickness 0.15)
				)
			)
		)
		(property "Val" "200k"
			(at 181.18 328.78 0)
			(layer "F.Fab")
			(hide yes)
			(effects
				(font
					(size 1 1)
					(thickness 0.15)
				)
			)
		)
		(sheetname "/Interfaces/")
		(sheetfile "interfaces.kicad_sch")
		(attr smd)
		(fp_rect
			(start -0.925 -0.47)
			(end 0.925 0.47)
			(stroke
				(width 0.05)
				(type default)
			)
			(fill no)
			(layer "F.CrtYd")
		)
		(fp_rect
			(start -0.5 -0.25)
			(end 0.5 0.25)
			(stroke
				(width 0.15)
				(type solid)
			)
			(fill no)
			(layer "F.Fab")
		)
		(pad "1" smd roundrect
			(at -0.48 0 180)
			(size 0.59 0.64)
			(layers "F.Cu" "F.Mask" "F.Paste")
			(roundrect_rratio 0.25)
			(net 338 "Net-(U22-EN)")
			(pintype "passive")
		)
		(pad "2" smd roundrect
			(at 0.48 0 180)
			(size 0.59 0.64)
			(layers "F.Cu" "F.Mask" "F.Paste")
			(roundrect_rratio 0.25)
			(net 2 "VCC3V3")
			(pintype "passive")
		)
	)
)
